#ISCELL
  mstr_symbols cad_note *
  *
#ISCELL
  mstr_symbols intel_corp_bpage *
  *
#ISCELL
  mstr_standard offpage *
  page268_i1
#ISCELL
  mstr_symbols gnd *
  page268_i10
#ISCELL
  mstr_symbols p3v3_stby *
  page268_i11
#CELL
  mstr_ttl ttl1g07_a *
  page268_i12
#CELL
  mstr_ttl ttl1g07_a *
  page268_i13
#CELL
  mstr_discrete res *
  page268_i14
#ISCELL
  mstr_symbols gnd *
  page268_i15
#ISCELL
  mstr_symbols gnd *
  page268_i16
#CELL
  mstr_discrete res *
  page268_i17
#ISCELL
  mstr_standard offpage *
  page268_i18
#ISCELL
  mstr_standard offpage *
  page268_i19
#CELL
  mstr_discrete res *
  page268_i2
#ISCELL
  mstr_symbols gnd *
  page268_i20
#ISCELL
  mstr_symbols gnd *
  page268_i21
#ISCELL
  mstr_symbols p3v3_stby *
  page268_i22
#CELL
  mstr_discrete cap *
  page268_i23
#ISCELL
  mstr_symbols gnd *
  page268_i25
#CELL
  mstr_discrete res *
  page268_i26
#CELL
  dev_discrete cap_a *
  page268_i27
#CELL
  mstr_discrete res *
  page268_i28
#CELL
  mstr_discrete res *
  page268_i29
#ISCELL
  mstr_symbols p3v3_stby *
  page268_i3
#ISCELL
  mstr_symbols p1v05_pch_stby *
  page268_i30
#ISCELL
  mstr_standard offpage *
  page268_i31
#ISCELL
  mstr_symbols gnd *
  page268_i32
#CELL
  mstr_digital gtl2014 *
  page268_i33
#ISCELL
  mstr_standard offpage *
  page268_i34
#ISCELL
  mstr_standard offpage *
  page268_i35
#CELL
  w_hdl 374r2f-1-gp *
  page268_i36
#ISCELL
  mstr_symbols p3v3_stby *
  page268_i37
#CELL
  mstr_ttl ttl3126 *
  page268_i38
#ISCELL
  mstr_symbols p3v3_stby *
  page268_i39
#CELL
  dev_discrete cap_a *
  page268_i4
#CELL
  mstr_discrete cap *
  page268_i40
#ISCELL
  mstr_symbols gnd *
  page268_i41
#ISCELL
  mstr_standard offpage *
  page268_i42
#ISCELL
  mstr_standard offpage *
  page268_i44
#ISCELL
  mstr_standard offpage *
  page268_i45
#ISCELL
  mstr_standard offpage *
  page268_i46
#ISCELL
  mstr_standard offpage *
  page268_i47
#ISCELL
  mstr_standard offpage *
  page268_i48
#ISCELL
  mstr_standard offpage *
  page268_i49
#ISCELL
  mstr_symbols gnd *
  page268_i5
#ISCELL
  mstr_standard offpage *
  page268_i50
#CELL
  mstr_discrete fet_n *
  page268_i51
#ISCELL
  mstr_symbols gnd *
  page268_i52
#ISCELL
  mstr_standard offpage *
  page268_i53
#CELL
  mstr_discrete res *
  page268_i54
#ISCELL
  mstr_symbols p3v3_stby *
  page268_i55
#CELL
  mstr_ttl ttl1g08 *
  page268_i57
#ISCELL
  mstr_symbols p3v3_stby *
  page268_i58
#ISCELL
  mstr_symbols gnd *
  page268_i59
#ISCELL
  mstr_symbols p3v3_stby *
  page268_i6
#CELL
  dev_discrete cap_a *
  page268_i60
#ISCELL
  mstr_standard offpage *
  page268_i61
#ISCELL
  mstr_standard offpage *
  page268_i62
#CELL
  w_hdl sw-slide75-gp *
  page268_i63
#ISCELL
  mstr_symbols gnd *
  page268_i64
#ISCELL
  mstr_symbols gnd *
  page268_i65
#CELL
  mstr_discrete res *
  page268_i66
#ISCELL
  mstr_standard offpage *
  page268_i67
#CELL
  mstr_discrete res *
  page268_i7
#ISCELL
  mstr_symbols p3v3_stby *
  page268_i8
#CELL
  dev_discrete cap_a *
  page268_i9
